(kicad_pcb
	(version 20241229)
	(generator "pcbnew")
	(generator_version "9.0")
	(general
		(thickness 1.61)
		(legacy_teardrops no)
	)
	(paper "A3")
	(title_block
		(title "RDIMM DDR5 Tester")
		(date "2026-05-21")
		(rev "2.2.0")
		(company "Antmicro")
		(comment 9 "footprints 489-493 of 796")
	)
	(layers
		(0 "F.Cu" signal)
		(4 "In1.Cu" power)
		(6 "In2.Cu" mixed)
		(8 "In3.Cu" power)
		(10 "In4.Cu" mixed)
		(12 "In5.Cu" power)
		(14 "In6.Cu" mixed)
		(16 "In7.Cu" power)
		(18 "In8.Cu" power)
		(20 "In9.Cu" mixed)
		(22 "In10.Cu" power)
		(2 "B.Cu" signal)
		(9 "F.Adhes" user "F.Adhesive")
		(11 "B.Adhes" user "B.Adhesive")
		(13 "F.Paste" user)
		(15 "B.Paste" user)
		(5 "F.SilkS" user "F.Silkscreen")
		(7 "B.SilkS" user "B.Silkscreen")
		(1 "F.Mask" user)
		(3 "B.Mask" user)
		(17 "Dwgs.User" user "User.Drawings")
		(19 "Cmts.User" user "User.Comments")
		(21 "Eco1.User" user "User.Eco1")
		(23 "Eco2.User" user "User.Eco2")
		(25 "Edge.Cuts" user)
		(27 "Margin" user)
		(31 "F.CrtYd" user "F.Courtyard")
		(29 "B.CrtYd" user "B.Courtyard")
		(35 "F.Fab" user)
		(33 "B.Fab" user)
	)
	(footprint "antmicro-footprints:R_0402_1005Metric"
		(layer "B.Cu")
		(at 125.92 186.94 180)
		(descr "Resistor SMD 0402")
		(tags "resistor SMD 0402")
		(property "Reference" "R237"
			(at 1.17 -0.46 0)
			(layer "B.SilkS")
			(effects
				(font
					(size 0.7 0.7)
					(thickness 0.15)
				)
				(justify left bottom mirror)
			)
		)
		(property "Value" "R_2k2_0402"
			(at -1.011843 -1.772047 0)
			(layer "B.Fab")
			(effects
				(font
					(size 0.7 0.7)
					(thickness 0.15)
				)
				(justify left bottom mirror)
			)
		)
		(property "Datasheet" "https://www.bourns.com/docs/product-datasheets/cr.pdf"
			(at 0 0 180)
			(layer "F.Fab")
			(hide yes)
			(effects
				(font
					(size 1.27 1.27)
					(thickness 0.15)
				)
			)
		)
		(property "MPN" "CR0402-FX-2201GLF"
			(at 0 0 180)
			(unlocked yes)
			(layer "B.Fab")
			(hide yes)
			(effects
				(font
					(size 1 1)
					(thickness 0.15)
				)
				(justify mirror)
			)
		)
		(property "Manufacturer" "Bourns"
			(at 0 0 180)
			(unlocked yes)
			(layer "B.Fab")
			(hide yes)
			(effects
				(font
					(size 1 1)
					(thickness 0.15)
				)
				(justify mirror)
			)
		)
		(property "License" "Apache-2.0"
			(at 0 0 180)
			(unlocked yes)
			(layer "B.Fab")
			(hide yes)
			(effects
				(font
					(size 1 1)
					(thickness 0.15)
				)
				(justify mirror)
			)
		)
		(property "Author" "Antmicro"
			(at 0 0 180)
			(unlocked yes)
			(layer "B.Fab")
			(hide yes)
			(effects
				(font
					(size 1 1)
					(thickness 0.15)
				)
				(justify mirror)
			)
		)
		(property "Val" "2k2"
			(at 0 0 180)
			(unlocked yes)
			(layer "B.Fab")
			(hide yes)
			(effects
				(font
					(size 1 1)
					(thickness 0.15)
				)
				(justify mirror)
			)
		)
		(property "Tolerance" "1%"
			(at 0 0 180)
			(unlocked yes)
			(layer "B.Fab")
			(hide yes)
			(effects
				(font
					(size 1 1)
					(thickness 0.15)
				)
				(justify mirror)
			)
		)
		(property "Public" ""
			(at 0 0 180)
			(unlocked yes)
			(layer "B.Fab")
			(hide yes)
			(effects
				(font
					(size 1 1)
					(thickness 0.15)
				)
				(justify mirror)
			)
		)
		(sheetname "/HDMI + SD Card/")
		(sheetfile "hdmi-sd-card.kicad_sch")
		(attr smd)
		(fp_rect
			(start -0.925 0.47)
			(end 0.925 -0.47)
			(stroke
				(width 0.05)
				(type default)
			)
			(fill no)
			(layer "B.CrtYd")
		)
		(fp_rect
			(start -0.5 0.25)
			(end 0.5 -0.25)
			(stroke
				(width 0.15)
				(type solid)
			)
			(fill no)
			(layer "B.Fab")
		)
		(fp_text user "License: Apache-2.0"
			(at -0.95 -5.169 0)
			(layer "B.Fab")
			(effects
				(font
					(size 0.7 0.7)
					(thickness 0.15)
				)
				(justify left bottom mirror)
			)
		)
		(fp_text user "${REFERENCE}"
			(at -0.95 -3.168 0)
			(layer "B.Fab")
			(effects
				(font
					(size 0.7 0.7)
					(thickness 0.15)
				)
				(justify left bottom mirror)
			)
		)
		(fp_text user "Author: Antmicro"
			(at -0.95 -4.169 0)
			(layer "B.Fab")
			(effects
				(font
					(size 0.7 0.7)
					(thickness 0.15)
				)
				(justify left bottom mirror)
			)
		)
		(pad "1" smd roundrect
			(at -0.48 0 180)
			(size 0.59 0.64)
			(layers "B.Cu" "B.Mask" "B.Paste")
			(roundrect_rratio 0.25)
			(net 644 "/FPGA banks HD/HDMI_OUT_I2C.SDA")
			(pintype "passive")
		)
		(pad "2" smd roundrect
			(at 0.48 0 180)
			(size 0.59 0.64)
			(layers "B.Cu" "B.Mask" "B.Paste")
			(roundrect_rratio 0.25)
			(net 151 "+3V3")
			(pintype "passive")
		)
	)
	(footprint "antmicro-footprints:R_0402_1005Metric"
		(layer "B.Cu")
		(at 125.92 187.94 180)
		(descr "Resistor SMD 0402")
		(tags "resistor SMD 0402")
		(property "Reference" "R236"
			(at 1.17 -0.46 0)
			(layer "B.SilkS")
			(effects
				(font
					(size 0.7 0.7)
					(thickness 0.15)
				)
				(justify left bottom mirror)
			)
		)
		(property "Value" "R_2k2_0402"
			(at -1.011843 -1.772047 0)
			(layer "B.Fab")
			(effects
				(font
					(size 0.7 0.7)
					(thickness 0.15)
				)
				(justify left bottom mirror)
			)
		)
		(property "Datasheet" "https://www.bourns.com/docs/product-datasheets/cr.pdf"
			(at 0 0 180)
			(layer "F.Fab")
			(hide yes)
			(effects
				(font
					(size 1.27 1.27)
					(thickness 0.15)
				)
			)
		)
		(property "MPN" "CR0402-FX-2201GLF"
			(at 0 0 180)
			(unlocked yes)
			(layer "B.Fab")
			(hide yes)
			(effects
				(font
					(size 1 1)
					(thickness 0.15)
				)
				(justify mirror)
			)
		)
		(property "Manufacturer" "Bourns"
			(at 0 0 180)
			(unlocked yes)
			(layer "B.Fab")
			(hide yes)
			(effects
				(font
					(size 1 1)
					(thickness 0.15)
				)
				(justify mirror)
			)
		)
		(property "License" "Apache-2.0"
			(at 0 0 180)
			(unlocked yes)
			(layer "B.Fab")
			(hide yes)
			(effects
				(font
					(size 1 1)
					(thickness 0.15)
				)
				(justify mirror)
			)
		)
		(property "Author" "Antmicro"
			(at 0 0 180)
			(unlocked yes)
			(layer "B.Fab")
			(hide yes)
			(effects
				(font
					(size 1 1)
					(thickness 0.15)
				)
				(justify mirror)
			)
		)
		(property "Val" "2k2"
			(at 0 0 180)
			(unlocked yes)
			(layer "B.Fab")
			(hide yes)
			(effects
				(font
					(size 1 1)
					(thickness 0.15)
				)
				(justify mirror)
			)
		)
		(property "Tolerance" "1%"
			(at 0 0 180)
			(unlocked yes)
			(layer "B.Fab")
			(hide yes)
			(effects
				(font
					(size 1 1)
					(thickness 0.15)
				)
				(justify mirror)
			)
		)
		(property "Public" ""
			(at 0 0 180)
			(unlocked yes)
			(layer "B.Fab")
			(hide yes)
			(effects
				(font
					(size 1 1)
					(thickness 0.15)
				)
				(justify mirror)
			)
		)
		(sheetname "/HDMI + SD Card/")
		(sheetfile "hdmi-sd-card.kicad_sch")
		(attr smd)
		(fp_rect
			(start -0.925 0.47)
			(end 0.925 -0.47)
			(stroke
				(width 0.05)
				(type default)
			)
			(fill no)
			(layer "B.CrtYd")
		)
		(fp_rect
			(start -0.5 0.25)
			(end 0.5 -0.25)
			(stroke
				(width 0.15)
				(type solid)
			)
			(fill no)
			(layer "B.Fab")
		)
		(fp_text user "${REFERENCE}"
			(at -0.95 -3.168 0)
			(layer "B.Fab")
			(effects
				(font
					(size 0.7 0.7)
					(thickness 0.15)
				)
				(justify left bottom mirror)
			)
		)
		(fp_text user "License: Apache-2.0"
			(at -0.95 -5.169 0)
			(layer "B.Fab")
			(effects
				(font
					(size 0.7 0.7)
					(thickness 0.15)
				)
				(justify left bottom mirror)
			)
		)
		(fp_text user "Author: Antmicro"
			(at -0.95 -4.169 0)
			(layer "B.Fab")
			(effects
				(font
					(size 0.7 0.7)
					(thickness 0.15)
				)
				(justify left bottom mirror)
			)
		)
		(pad "1" smd roundrect
			(at -0.48 0 180)
			(size 0.59 0.64)
			(layers "B.Cu" "B.Mask" "B.Paste")
			(roundrect_rratio 0.25)
			(net 554 "/FPGA banks HD/HDMI_OUT_I2C.SCL")
			(pintype "passive")
		)
		(pad "2" smd roundrect
			(at 0.48 0 180)
			(size 0.59 0.64)
			(layers "B.Cu" "B.Mask" "B.Paste")
			(roundrect_rratio 0.25)
			(net 151 "+3V3")
			(pintype "passive")
		)
	)
	(footprint "antmicro-footprints:C_0805_2012Metric"
		(layer "B.Cu")
		(at 178.000001 167.5 180)
		(descr "Capacitor SMD 0805")
		(tags "capacitor SMD 0805")
		(property "Reference" "C54"
			(at -0.499999 -1.8 0)
			(layer "B.SilkS")
			(effects
				(font
					(size 0.7 0.7)
					(thickness 0.15)
				)
				(justify left bottom mirror)
			)
		)
		(property "Value" "C_100u_0805"
			(at -2.055717 -1.963152 0)
			(layer "B.Fab")
			(effects
				(font
					(size 0.7 0.7)
					(thickness 0.15)
				)
				(justify left bottom mirror)
			)
		)
		(property "Datasheet" "https://www.murata.com/products/productdetail?partno=GRM21BR60J107ME15%23"
			(at 0 0 180)
			(layer "F.Fab")
			(hide yes)
			(effects
				(font
					(size 1.27 1.27)
					(thickness 0.15)
				)
			)
		)
		(property "MPN" "GRM21BR60J107ME15L"
			(at 0 0 180)
			(unlocked yes)
			(layer "B.Fab")
			(hide yes)
			(effects
				(font
					(size 1 1)
					(thickness 0.15)
				)
				(justify mirror)
			)
		)
		(property "Manufacturer" "Murata"
			(at 0 0 180)
			(unlocked yes)
			(layer "B.Fab")
			(hide yes)
			(effects
				(font
					(size 1 1)
					(thickness 0.15)
				)
				(justify mirror)
			)
		)
		(property "License" "Apache-2.0"
			(at 0 0 180)
			(unlocked yes)
			(layer "B.Fab")
			(hide yes)
			(effects
				(font
					(size 1 1)
					(thickness 0.15)
				)
				(justify mirror)
			)
		)
		(property "Author" "Antmicro"
			(at 0 0 180)
			(unlocked yes)
			(layer "B.Fab")
			(hide yes)
			(effects
				(font
					(size 1 1)
					(thickness 0.15)
				)
				(justify mirror)
			)
		)
		(property "Val" "100u"
			(at 0 0 180)
			(unlocked yes)
			(layer "B.Fab")
			(hide yes)
			(effects
				(font
					(size 1 1)
					(thickness 0.15)
				)
				(justify mirror)
			)
		)
		(property "Voltage" ""
			(at 0 0 180)
			(unlocked yes)
			(layer "B.Fab")
			(hide yes)
			(effects
				(font
					(size 1 1)
					(thickness 0.15)
				)
				(justify mirror)
			)
		)
		(property "Dielectric" ""
			(at 0 0 180)
			(unlocked yes)
			(layer "B.Fab")
			(hide yes)
			(effects
				(font
					(size 1 1)
					(thickness 0.15)
				)
				(justify mirror)
			)
		)
		(property "Public" "False"
			(at 0 0 180)
			(unlocked yes)
			(layer "B.Fab")
			(hide yes)
			(effects
				(font
					(size 1 1)
					(thickness 0.15)
				)
				(justify mirror)
			)
		)
		(sheetname "/FPGA power/")
		(sheetfile "fpga-power.kicad_sch")
		(attr smd)
		(fp_line
			(start -0.3 0.7)
			(end 0.3 0.7)
			(stroke
				(width 0.15)
				(type solid)
			)
			(layer "B.SilkS")
		)
		(fp_line
			(start -0.3 -0.7)
			(end 0.3 -0.7)
			(stroke
				(width 0.15)
				(type solid)
			)
			(layer "B.SilkS")
		)
		(fp_rect
			(start 1.95 0.9)
			(end -1.95 -0.9)
			(stroke
				(width 0.05)
				(type default)
			)
			(fill no)
			(layer "B.CrtYd")
		)
		(fp_rect
			(start -0.95 0.675)
			(end 0.95 -0.675)
			(stroke
				(width 0.15)
				(type solid)
			)
			(fill no)
			(layer "B.Fab")
		)
		(fp_text user "Author: Antmicro"
			(at -1.9 -5.947 0)
			(layer "B.Fab")
			(effects
				(font
					(size 0.7 0.7)
					(thickness 0.15)
				)
				(justify left bottom mirror)
			)
		)
		(fp_text user "License: Apache-2.0"
			(at -1.9 -4.947 0)
			(layer "B.Fab")
			(effects
				(font
					(size 0.7 0.7)
					(thickness 0.15)
				)
				(justify left bottom mirror)
			)
		)
		(fp_text user "${REFERENCE}"
			(at -1.9 -3.947 0)
			(layer "B.Fab")
			(effects
				(font
					(size 0.7 0.7)
					(thickness 0.15)
				)
				(justify left bottom mirror)
			)
		)
		(pad "1" smd roundrect
			(at -1.1 0 180)
			(size 1.2 1.3)
			(layers "B.Cu" "B.Mask" "B.Paste")
			(roundrect_rratio 0.25)
			(net 1 "GND")
			(pintype "passive")
		)
		(pad "2" smd roundrect
			(at 1.1 0 180)
			(size 1.2 1.3)
			(layers "B.Cu" "B.Mask" "B.Paste")
			(roundrect_rratio 0.25)
			(net 553 "+0V85")
			(pintype "passive")
		)
	)
	(footprint "antmicro-footprints:NetTie-2_SMD_Pad0.127mm"
		(layer "B.Cu")
		(at 222.135 176.66 90)
		(descr "Net tie, 2 pin, 0.127mm  SMD pads")
		(tags "net tie")
		(property "Reference" "TP24"
			(at 1.36 -0.085 90)
			(layer "B.SilkS")
			(hide yes)
			(effects
				(font
					(size 0.7 0.7)
					(thickness 0.15)
				)
				(justify right bottom mirror)
			)
		)
		(property "Value" "Net-Tie_P0.127mm"
			(at 0 -1.199 90)
			(layer "B.Fab")
			(effects
				(font
					(size 0.7 0.7)
					(thickness 0.15)
				)
				(justify right bottom mirror)
			)
		)
		(property "MPN" ""
			(at 0 0 90)
			(unlocked yes)
			(layer "B.Fab")
			(hide yes)
			(effects
				(font
					(size 1 1)
					(thickness 0.15)
				)
				(justify mirror)
			)
		)
		(property "Manufacturer" ""
			(at 0 0 90)
			(unlocked yes)
			(layer "B.Fab")
			(hide yes)
			(effects
				(font
					(size 1 1)
					(thickness 0.15)
				)
				(justify mirror)
			)
		)
		(property "Author" "Antmicro"
			(at 0 0 90)
			(unlocked yes)
			(layer "B.Fab")
			(hide yes)
			(effects
				(font
					(size 1 1)
					(thickness 0.15)
				)
				(justify mirror)
			)
		)
		(property "License" "Apache-2.0"
			(at 0 0 90)
			(unlocked yes)
			(layer "B.Fab")
			(hide yes)
			(effects
				(font
					(size 1 1)
					(thickness 0.15)
				)
				(justify mirror)
			)
		)
		(property ki_fp_filters "Net*Tie*")
		(sheetname "/Supply/DC-DC VCCINT/")
		(sheetfile "dc-dc-vccint.kicad_sch")
		(attr through_hole exclude_from_pos_files exclude_from_bom)
		(net_tie_pad_groups "1, 2")
		(fp_poly
			(pts
				(xy -0.0635 0.0635) (xy 0.0625 0.0635) (xy 0.0625 -0.0635) (xy -0.0635 -0.0635)
			)
			(stroke
				(width 0)
				(type solid)
			)
			(fill yes)
			(layer "B.Cu")
		)
		(fp_poly
			(pts
				(xy 0.2 0.16) (xy 0.29 0.07) (xy 0.29 -0.07) (xy 0.2 -0.16) (xy -0.2 -0.16) (xy -0.29 -0.07) (xy -0.29 0.06)
				(xy -0.19 0.16)
			)
			(stroke
				(width 0.05)
				(type solid)
			)
			(fill no)
			(layer "B.CrtYd")
		)
		(fp_text user "${REFERENCE}"
			(at -0.128 -3.2 270)
			(layer "B.Fab")
			(effects
				(font
					(size 0.7 0.7)
					(thickness 0.15)
				)
				(justify left bottom mirror)
			)
		)
		(fp_text user "License: Apache-2.0"
			(at -0.128 -5.6 270)
			(layer "B.Fab")
			(effects
				(font
					(size 0.7 0.7)
					(thickness 0.15)
				)
				(justify left bottom mirror)
			)
		)
		(fp_text user "Author: Antmicro"
			(at -0.128 -4.4 270)
			(layer "B.Fab")
			(effects
				(font
					(size 0.7 0.7)
					(thickness 0.15)
				)
				(justify left bottom mirror)
			)
		)
		(pad "1" smd roundrect
			(at -0.127 0 270)
			(size 0.127 0.127)
			(layers "B.Cu")
			(roundrect_rratio 0.5)
			(chamfer_ratio 0)
			(chamfer top_left bottom_left)
			(net 754 "/Supply/DC-DC VCCINT/VREF+")
			(pinfunction "1")
			(pintype "passive")
		)
		(pad "2" smd roundrect
			(at 0.126 0 90)
			(size 0.127 0.127)
			(layers "B.Cu")
			(roundrect_rratio 0.5)
			(chamfer_ratio 0)
			(chamfer top_left bottom_left)
			(net 553 "+0V85")
			(pinfunction "2")
			(pintype "passive")
		)
	)
	(footprint "antmicro-footprints:R_0402_1005Metric"
		(layer "B.Cu")
		(at 240.675 157.605 -90)
		(descr "Resistor SMD 0402")
		(tags "resistor SMD 0402")
		(property "Reference" "R173"
			(at 0.875 -0.485 90)
			(layer "B.SilkS")
			(effects
				(font
					(size 0.7 0.7)
					(thickness 0.15)
				)
				(justify left bottom mirror)
			)
		)
		(property "Value" "R_47k_0402"
			(at -1.011843 -1.772047 90)
			(layer "B.Fab")
			(effects
				(font
					(size 0.7 0.7)
					(thickness 0.15)
				)
				(justify left bottom mirror)
			)
		)
		(property "Datasheet" "https://www.bourns.com/docs/product-datasheets/cr.pdf"
			(at 0 0 270)
			(layer "F.Fab")
			(hide yes)
			(effects
				(font
					(size 1.27 1.27)
					(thickness 0.15)
				)
			)
		)
		(property "Manufacturer" "Bourns"
			(at 0 0 270)
			(unlocked yes)
			(layer "B.Fab")
			(hide yes)
			(effects
				(font
					(size 1 1)
					(thickness 0.15)
				)
				(justify mirror)
			)
		)
		(property "MPN" "CR0402-FX-4702GLF"
			(at 0 0 270)
			(unlocked yes)
			(layer "B.Fab")
			(hide yes)
			(effects
				(font
					(size 1 1)
					(thickness 0.15)
				)
				(justify mirror)
			)
		)
		(property "Val" "47k"
			(at 0 0 270)
			(unlocked yes)
			(layer "B.Fab")
			(hide yes)
			(effects
				(font
					(size 1 1)
					(thickness 0.15)
				)
				(justify mirror)
			)
		)
		(property "License" "Apache-2.0"
			(at 0 0 270)
			(unlocked yes)
			(layer "B.Fab")
			(hide yes)
			(effects
				(font
					(size 1 1)
					(thickness 0.15)
				)
				(justify mirror)
			)
		)
		(property "Author" "Antmicro"
			(at 0 0 270)
			(unlocked yes)
			(layer "B.Fab")
			(hide yes)
			(effects
				(font
					(size 1 1)
					(thickness 0.15)
				)
				(justify mirror)
			)
		)
		(property "Tolerance" "1%"
			(at 0 0 270)
			(unlocked yes)
			(layer "B.Fab")
			(hide yes)
			(effects
				(font
					(size 1 1)
					(thickness 0.15)
				)
				(justify mirror)
			)
		)
		(sheetname "/Supply/DC-DC IO/")
		(sheetfile "dc-dc-io.kicad_sch")
		(attr smd)
		(fp_rect
			(start -0.925 0.47)
			(end 0.925 -0.47)
			(stroke
				(width 0.05)
				(type default)
			)
			(fill no)
			(layer "B.CrtYd")
		)
		(fp_rect
			(start -0.5 0.25)
			(end 0.5 -0.25)
			(stroke
				(width 0.15)
				(type solid)
			)
			(fill no)
			(layer "B.Fab")
		)
		(fp_text user "${REFERENCE}"
			(at -0.95 -3.168 90)
			(layer "B.Fab")
			(effects
				(font
					(size 0.7 0.7)
					(thickness 0.15)
				)
				(justify left bottom mirror)
			)
		)
		(fp_text user "Author: Antmicro"
			(at -0.95 -4.169 90)
			(layer "B.Fab")
			(effects
				(font
					(size 0.7 0.7)
					(thickness 0.15)
				)
				(justify left bottom mirror)
			)
		)
		(fp_text user "License: Apache-2.0"
			(at -0.95 -5.169 90)
			(layer "B.Fab")
			(effects
				(font
					(size 0.7 0.7)
					(thickness 0.15)
				)
				(justify left bottom mirror)
			)
		)
		(pad "1" smd roundrect
			(at -0.48 0 270)
			(size 0.59 0.64)
			(layers "B.Cu" "B.Mask" "B.Paste")
			(roundrect_rratio 0.25)
			(net 720 "Net-(U28-~{PWRDN})")
			(pintype "passive")
		)
		(pad "2" smd roundrect
			(at 0.48 0 270)
			(size 0.59 0.64)
			(layers "B.Cu" "B.Mask" "B.Paste")
			(roundrect_rratio 0.25)
			(net 38 "+3V3_AON")
			(pintype "passive")
		)
	)
)
